# S9S_MB_2U (Grand Teton) — schematic netlist excerpt (pin names and nets, part order shuffled) for the footprints in the layout excerpt that follows; sources: Cadence DE-HDL packaged netlist, KiCad conversion of 03242023_DA0F0TMBIJ0_F0T_Motherboard_J_brd_V01_OCP.brd

PU293  MP5016GQHLZ  MP5016GQH-L-Z EMPTY  pkg QFN8_2X1-5  page 193
  VCC  = P3V3_AUX
  GND  = GND
  ILIMIT  = P3V3_E1S_ILIMIT_0
  MODE  = P3V3_E1S_MODE_0
  SOURCE  = P3V3_E1S_0_R
  GATE  = P3V3_E1S_GATE_0_PU293
  EN  = P3V3_E1S_EN_0_R2
  DV_DT  = P3V3_E1S_DVDT_0

PC318  Q_CAPP  270UF 16V 20% OSCON  pkg THLF  page 267 : A = SW_P12V_PVCCIN_CPU0_FLT ; B = GND
R990  Q_RES  2K 1% CHIP  pkg 0402LF  page 219 : A = FM_PLD_CLK_25M_R_EN ; B = GND

(kicad_pcb
	(version 20260206)
	(generator "pcbnew")
	(generator_version "10.0")
	(general
		(thickness 1.6)
		(legacy_teardrops no)
	)
	(paper "A4")
	(title_block
		(title "03242023_DA0F0TMBIJ0_F0T_Motherboard_J_brd_V01_OCP.brd")
		(comment 1 "Grand Teton / footprints 3292-3294 of 6105")
	)
	(layers
		(0 "F.Cu" signal "TOP")
		(4 "In1.Cu" signal "GND")
		(6 "In2.Cu" signal "IN1")
		(8 "In3.Cu" signal "GND1")
		(10 "In4.Cu" signal "IN2")
		(12 "In5.Cu" signal "GND2")
		(14 "In6.Cu" signal "IN3")
		(16 "In7.Cu" signal "GND3")
		(18 "In8.Cu" signal "VCC")
		(20 "In9.Cu" signal "VCC1")
		(22 "In10.Cu" signal "GND4")
		(24 "In11.Cu" signal "IN4")
		(26 "In12.Cu" signal "GND5")
		(28 "In13.Cu" signal "IN5")
		(30 "In14.Cu" signal "GND6")
		(32 "In15.Cu" signal "IN6")
		(34 "In16.Cu" signal "GND7")
		(2 "B.Cu" signal "BOTTOM")
		(9 "F.Adhes" user "F.Adhesive")
		(11 "B.Adhes" user "B.Adhesive")
		(13 "F.Paste" user "Package Geometry/Pastemask Top")
		(15 "B.Paste" user "Package Geometry/Pastemask Bottom")
		(5 "F.SilkS" user "Ref Des/Silkscreen Top")
		(7 "B.SilkS" user "Ref Des/Silkscreen Bottom")
		(1 "F.Mask" user "Board Geometry/Soldermask Top")
		(3 "B.Mask" user "Board Geometry/Soldermask Bottom")
		(17 "Dwgs.User" user "User.Drawings")
		(19 "Cmts.User" user "User.Comments")
		(21 "Eco1.User" user "User.Eco1")
		(23 "Eco2.User" user "User.Eco2")
		(25 "Edge.Cuts" user "Board Geometry/Outline")
		(27 "Margin" user)
		(31 "F.CrtYd" user "Package Geometry/Place Bound Top")
		(29 "B.CrtYd" user "Package Geometry/Place Bound Bottom")
		(35 "F.Fab" user "Ref Des/Assembly Top")
		(33 "B.Fab" user "Ref Des/Assembly Bottom")
	)
	(footprint ""
		(layer "F.Cu")
		(at 194.35064 -69.423788 -90)
		(property "Reference" "PU293"
			(at 3.817112 3.85572 0)
			(unlocked yes)
			(layer "F.SilkS")
			(effects
				(font
					(size 0.7874 0.5842)
					(thickness 0.1524)
				)
			)
		)
		(property "Value" ""
			(at 0 0 270)
			(layer "F.Fab")
			(effects
				(font
					(size 1.27 1.27)
				)
			)
		)
		(duplicate_pad_numbers_are_jumpers no)
		(fp_line
			(start -1.239774 1.495298)
			(end -1.239774 -1.495298)
			(stroke
				(width 0.1524)
				(type default)
			)
			(layer "F.SilkS")
		)
		(fp_line
			(start 1.239774 1.495298)
			(end -1.239774 1.495298)
			(stroke
				(width 0.1524)
				(type default)
			)
			(layer "F.SilkS")
		)
		(fp_line
			(start -1.239774 -1.495298)
			(end 1.239774 -1.495298)
			(stroke
				(width 0.1524)
				(type default)
			)
			(layer "F.SilkS")
		)
		(fp_line
			(start 1.239774 -1.495298)
			(end 1.239774 1.495298)
			(stroke
				(width 0.1524)
				(type default)
			)
			(layer "F.SilkS")
		)
		(fp_poly
			(pts
				(xy -1.754124 -1.697228) (xy -1.394968 -0.619506) (xy -2.472436 -0.978662)
			)
			(stroke
				(width 0)
				(type default)
			)
			(fill yes)
			(layer "F.SilkS")
		)
		(fp_line
			(start -0.8001 1.050036)
			(end -0.8001 -1.050036)
			(stroke
				(width 0.1)
				(type default)
			)
			(layer "F.Fab")
		)
		(fp_line
			(start 0.8001 1.050036)
			(end -0.8001 1.050036)
			(stroke
				(width 0.1)
				(type default)
			)
			(layer "F.Fab")
		)
		(fp_line
			(start -0.8001 -1.050036)
			(end 0.8001 -1.050036)
			(stroke
				(width 0.1)
				(type default)
			)
			(layer "F.Fab")
		)
		(fp_line
			(start 0.8001 -1.050036)
			(end 0.8001 1.050036)
			(stroke
				(width 0.1)
				(type default)
			)
			(layer "F.Fab")
		)
		(fp_poly
			(pts
				(xy -2.458974 -0.508) (xy -2.458974 0.508) (xy -1.442974 0)
			)
			(stroke
				(width 0)
				(type default)
			)
			(fill yes)
			(layer "F.Fab")
		)
		(pad "1_2" smd circle
			(at -0.374904 0)
			(size 0 0)
			(layers "F.Cu" "F.Mask" "F.Paste")
			(net "P3V3_AUX")
		)
		(pad "3" smd rect
			(at -0.499872 0.999998 270)
			(size 0.254 0.7112)
			(layers "F.Cu" "F.Mask" "F.Paste")
			(net "GND")
		)
		(pad "4" smd rect
			(at 0 0.999998 270)
			(size 0.254 0.7112)
			(layers "F.Cu" "F.Mask" "F.Paste")
			(net "P3V3_E1S_ILIMIT_0")
		)
		(pad "5" smd rect
			(at 0.499872 0.999998 270)
			(size 0.254 0.7112)
			(layers "F.Cu" "F.Mask" "F.Paste")
			(net "P3V3_E1S_MODE_0")
		)
		(pad "6_7" smd circle
			(at 0.374904 0 180)
			(size 0 0)
			(layers "F.Cu" "F.Mask" "F.Paste")
			(net "P3V3_E1S_0_R")
		)
		(pad "8" smd rect
			(at 0.499872 -0.999998 270)
			(size 0.254 0.7112)
			(layers "F.Cu" "F.Mask" "F.Paste")
			(net "P3V3_E1S_GATE_0_PU293")
		)
		(pad "9" smd rect
			(at 0 -0.999998 270)
			(size 0.254 0.7112)
			(layers "F.Cu" "F.Mask" "F.Paste")
			(net "P3V3_E1S_EN_0_R2")
		)
		(pad "10" smd rect
			(at -0.499872 -0.999998 270)
			(size 0.254 0.7112)
			(layers "F.Cu" "F.Mask" "F.Paste")
			(net "P3V3_E1S_DVDT_0")
		)
	)
	(footprint ""
		(layer "F.Cu")
		(at 345.27871 -343.902284 90)
		(property "Reference" "PC318"
			(at 0 0 90)
			(layer "F.SilkS")
			(hide yes)
			(effects
				(font
					(size 1.27 1.27)
				)
			)
		)
		(property "Value" ""
			(at 0 0 90)
			(layer "F.Fab")
			(effects
				(font
					(size 1.27 1.27)
				)
			)
		)
		(duplicate_pad_numbers_are_jumpers no)
		(fp_line
			(start -3.400044 1.249934)
			(end 3.400044 1.249934)
			(stroke
				(width 0.1524)
				(type default)
			)
			(layer "F.SilkS")
		)
		(fp_circle
			(center 0 1.249934)
			(end 0 4.649978)
			(stroke
				(width 0.1524)
				(type default)
			)
			(fill no)
			(layer "F.SilkS")
		)
		(fp_poly
			(pts
				(arc
					(start -3.400044 1.249934)
					(mid 0 4.649978)
					(end 3.400044 1.249934)
				)
			)
			(stroke
				(width 0)
				(type default)
			)
			(fill yes)
			(layer "F.SilkS")
		)
		(fp_circle
			(center 0 1.249934)
			(end 0 4.649978)
			(stroke
				(width 0.1)
				(type default)
			)
			(fill no)
			(layer "F.Fab")
		)
		(pad "1" thru_hole rect
			(at 0 0 90)
			(size 1.524 1.524)
			(drill 1.016)
			(layers "*.Cu" "*.Mask")
			(remove_unused_layers no)
			(net "SW_P12V_PVCCIN_CPU0_FLT")
			(clearance 0)
			(padstack
				(mode front_inner_back)
				(layer "Inner"
					(shape circle)
					(size 1.524 1.524)
					(clearance 0)
				)
				(layer "B.Cu"
					(shape rect)
					(size 1.524 1.524)
					(clearance 0)
				)
			)
		)
		(pad "2" thru_hole circle
			(at 0 2.500122 90)
			(size 1.524 1.524)
			(drill 1.016)
			(layers "*.Cu" "*.Mask")
			(remove_unused_layers no)
			(net "GND")
			(clearance 0)
		)
	)
	(footprint ""
		(layer "F.Cu")
		(at 197.41388 -106.225848)
		(property "Reference" "R990"
			(at 0 0 0)
			(layer "F.SilkS")
			(hide yes)
			(effects
				(font
					(size 1.27 1.27)
				)
			)
		)
		(property "Value" ""
			(at 0 0 0)
			(layer "F.Fab")
			(effects
				(font
					(size 1.27 1.27)
				)
			)
		)
		(duplicate_pad_numbers_are_jumpers no)
		(fp_line
			(start -0.7874 -0.4064)
			(end 0.7874 -0.4064)
			(stroke
				(width 0.1524)
				(type default)
			)
			(layer "F.SilkS")
		)
		(fp_line
			(start -0.7874 0.4064)
			(end -0.7874 -0.4064)
			(stroke
				(width 0.1524)
				(type default)
			)
			(layer "F.SilkS")
		)
		(fp_line
			(start 0.7874 -0.4064)
			(end 0.7874 0.4064)
			(stroke
				(width 0.1524)
				(type default)
			)
			(layer "F.SilkS")
		)
		(fp_line
			(start 0.7874 0.4064)
			(end -0.7874 0.4064)
			(stroke
				(width 0.1524)
				(type default)
			)
			(layer "F.SilkS")
		)
		(fp_line
			(start -0.67945 -0.305054)
			(end -0.12065 -0.305054)
			(stroke
				(width 0.1)
				(type default)
			)
			(layer "F.Fab")
		)
		(fp_line
			(start -0.67945 0.3048)
			(end -0.67945 -0.305054)
			(stroke
				(width 0.1)
				(type default)
			)
			(layer "F.Fab")
		)
		(fp_line
			(start -0.12065 -0.305054)
			(end -0.12065 -0.2794)
			(stroke
				(width 0.1)
				(type default)
			)
			(layer "F.Fab")
		)
		(fp_line
			(start -0.12065 -0.2794)
			(end 0.12065 -0.2794)
			(stroke
				(width 0.1)
				(type default)
			)
			(layer "F.Fab")
		)
		(fp_line
			(start -0.12065 0.2794)
			(end -0.12065 0.3048)
			(stroke
				(width 0.1)
				(type default)
			)
			(layer "F.Fab")
		)
		(fp_line
			(start -0.12065 0.3048)
			(end -0.67945 0.3048)
			(stroke
				(width 0.1)
				(type default)
			)
			(layer "F.Fab")
		)
		(fp_line
			(start 0.120396 0.2794)
			(end -0.12065 0.2794)
			(stroke
				(width 0.1)
				(type default)
			)
			(layer "F.Fab")
		)
		(fp_line
			(start 0.120396 0.3048)
			(end 0.120396 0.2794)
			(stroke
				(width 0.1)
				(type default)
			)
			(layer "F.Fab")
		)
		(fp_line
			(start 0.12065 -0.3048)
			(end 0.67945 -0.3048)
			(stroke
				(width 0.1)
				(type default)
			)
			(layer "F.Fab")
		)
		(fp_line
			(start 0.12065 -0.2794)
			(end 0.12065 -0.3048)
			(stroke
				(width 0.1)
				(type default)
			)
			(layer "F.Fab")
		)
		(fp_line
			(start 0.67945 -0.3048)
			(end 0.67945 0.3048)
			(stroke
				(width 0.1)
				(type default)
			)
			(layer "F.Fab")
		)
		(fp_line
			(start 0.67945 0.3048)
			(end 0.120396 0.3048)
			(stroke
				(width 0.1)
				(type default)
			)
			(layer "F.Fab")
		)
		(pad "1" smd circle
			(at -0.40005 0)
			(size 0 0)
			(layers "F.Cu" "F.Mask" "F.Paste")
			(net "FM_PLD_CLK_25M_R_EN")
		)
		(pad "2" smd circle
			(at 0.40005 0)
			(size 0 0)
			(layers "F.Cu" "F.Mask" "F.Paste")
			(net "GND")
		)
	)
)
